(kicad_pcb
	(version 20260206)
	(generator "pcbnew")
	(generator_version "10.0")
	(general
		(thickness 1.6)
		(legacy_teardrops no)
	)
	(paper "A4")
	(title_block
		(title "04192023_DAF0TMB3IC0_F0TG_MB_C_brd_V02_OCP.brd")
		(comment 1 "Grand Teton / footprint 1456 of 8354 (J29), pads 227-291 of 291")
	)
	(layers
		(0 "F.Cu" signal "TOP")
		(4 "In1.Cu" signal "GND")
		(6 "In2.Cu" signal "IN1")
		(8 "In3.Cu" signal "GND1")
		(10 "In4.Cu" signal "IN2")
		(12 "In5.Cu" signal "GND2")
		(14 "In6.Cu" signal "IN3")
		(16 "In7.Cu" signal "GND3")
		(18 "In8.Cu" signal "VCC")
		(20 "In9.Cu" signal "VCC1")
		(22 "In10.Cu" signal "GND4")
		(24 "In11.Cu" signal "IN4")
		(26 "In12.Cu" signal "GND5")
		(28 "In13.Cu" signal "IN5")
		(30 "In14.Cu" signal "GND6")
		(32 "In15.Cu" signal "IN6")
		(34 "In16.Cu" signal "GND7")
		(2 "B.Cu" signal "BOTTOM")
		(9 "F.Adhes" user "F.Adhesive")
		(11 "B.Adhes" user "B.Adhesive")
		(13 "F.Paste" user "Package Geometry/Pastemask Top")
		(15 "B.Paste" user "Package Geometry/Pastemask Bottom")
		(5 "F.SilkS" user "Ref Des/Silkscreen Top")
		(7 "B.SilkS" user "Ref Des/Silkscreen Bottom")
		(1 "F.Mask" user "Board Geometry/Soldermask Top")
		(3 "B.Mask" user "Board Geometry/Soldermask Bottom")
		(17 "Dwgs.User" user "User.Drawings")
		(19 "Cmts.User" user "User.Comments")
		(21 "Eco1.User" user "User.Eco1")
		(23 "Eco2.User" user "User.Eco2")
		(25 "Edge.Cuts" user "Board Geometry/Outline")
		(27 "Margin" user)
		(31 "F.CrtYd" user "Package Geometry/Place Bound Top")
		(29 "B.CrtYd" user "Package Geometry/Place Bound Bottom")
		(35 "F.Fab" user "Ref Des/Assembly Top")
		(33 "B.Fab" user "Ref Des/Assembly Bottom")
	)
	(footprint ""
		(layer "F.Cu")
		(at 189.110112 -255.560322 180)
		(property "Reference" "J29"
			(at -2.7178 -81.857088 0)
			(unlocked yes)
			(layer "F.SilkS")
			(effects
				(font
					(size 0.7874 0.5842)
					(thickness 0.1524)
				)
			)
		)
		(property "Value" ""
			(at 0 0 180)
			(layer "F.Fab")
			(effects
				(font
					(size 1.27 1.27)
				)
			)
		)
		(duplicate_pad_numbers_are_jumpers no)
		(pad "227" smd rect
			(at 2.050034 11.474958 90)
			(size 0.519938 1.4986)
			(layers "F.Cu" "F.Mask" "F.Paste")
			(net "M_J_CPU1_SB_PAR")
		)
		(pad "228" smd rect
			(at 2.050034 12.325096 90)
			(size 0.519938 1.4986)
			(layers "F.Cu" "F.Mask" "F.Paste")
			(net "GND")
		)
		(pad "229" smd rect
			(at 2.050034 13.17498 90)
			(size 0.519938 1.4986)
			(layers "F.Cu" "F.Mask" "F.Paste")
			(net "M_J_CPU1_SB_CS_N<1>")
		)
		(pad "230" smd rect
			(at 2.050034 14.025118 90)
			(size 0.519938 1.4986)
			(layers "F.Cu" "F.Mask" "F.Paste")
			(net "GND")
		)
		(pad "231" smd rect
			(at 2.050034 14.875002 90)
			(size 0.519938 1.4986)
			(layers "F.Cu" "F.Mask" "F.Paste")
			(net "Net_2387")
		)
		(pad "232" smd rect
			(at 2.050034 15.724886 90)
			(size 0.519938 1.4986)
			(layers "F.Cu" "F.Mask" "F.Paste")
			(net "Net_2388")
		)
		(pad "233" smd rect
			(at 2.050034 16.575024 90)
			(size 0.519938 1.4986)
			(layers "F.Cu" "F.Mask" "F.Paste")
			(net "GND")
		)
		(pad "234" smd rect
			(at 2.050034 17.424908 90)
			(size 0.519938 1.4986)
			(layers "F.Cu" "F.Mask" "F.Paste")
			(net "M_J_CPU1_SB_CB<6>")
		)
		(pad "235" smd rect
			(at 2.050034 18.275046 90)
			(size 0.519938 1.4986)
			(layers "F.Cu" "F.Mask" "F.Paste")
			(net "GND")
		)
		(pad "236" smd rect
			(at 2.050034 19.12493 90)
			(size 0.519938 1.4986)
			(layers "F.Cu" "F.Mask" "F.Paste")
			(net "M_J_CPU1_SB_CB<7>")
		)
		(pad "237" smd rect
			(at 2.050034 19.975068 90)
			(size 0.519938 1.4986)
			(layers "F.Cu" "F.Mask" "F.Paste")
			(net "GND")
		)
		(pad "238" smd rect
			(at 2.050034 20.824952 90)
			(size 0.519938 1.4986)
			(layers "F.Cu" "F.Mask" "F.Paste")
			(net "M_J_CPU1_SB_DQS_DN<4>")
		)
		(pad "239" smd rect
			(at 2.050034 21.67509 90)
			(size 0.519938 1.4986)
			(layers "F.Cu" "F.Mask" "F.Paste")
			(net "M_J_CPU1_SB_DQS_DP<4>")
		)
		(pad "240" smd rect
			(at 2.050034 22.524974 90)
			(size 0.519938 1.4986)
			(layers "F.Cu" "F.Mask" "F.Paste")
			(net "GND")
		)
		(pad "241" smd rect
			(at 2.050034 23.375112 90)
			(size 0.519938 1.4986)
			(layers "F.Cu" "F.Mask" "F.Paste")
			(net "M_J_CPU1_SB_CB<2>")
		)
		(pad "242" smd rect
			(at 2.050034 24.224996 90)
			(size 0.519938 1.4986)
			(layers "F.Cu" "F.Mask" "F.Paste")
			(net "GND")
		)
		(pad "243" smd rect
			(at 2.050034 25.07488 90)
			(size 0.519938 1.4986)
			(layers "F.Cu" "F.Mask" "F.Paste")
			(net "M_J_CPU1_SB_CB<3>")
		)
		(pad "244" smd rect
			(at 2.050034 25.925018 90)
			(size 0.519938 1.4986)
			(layers "F.Cu" "F.Mask" "F.Paste")
			(net "GND")
		)
		(pad "245" smd rect
			(at 2.050034 26.774902 90)
			(size 0.519938 1.4986)
			(layers "F.Cu" "F.Mask" "F.Paste")
			(net "M_J_CPU1_SB_DQ<2>")
		)
		(pad "246" smd rect
			(at 2.050034 27.62504 90)
			(size 0.519938 1.4986)
			(layers "F.Cu" "F.Mask" "F.Paste")
			(net "GND")
		)
		(pad "247" smd rect
			(at 2.050034 28.474924 90)
			(size 0.519938 1.4986)
			(layers "F.Cu" "F.Mask" "F.Paste")
			(net "M_J_CPU1_SB_DQ<3>")
		)
		(pad "248" smd rect
			(at 2.050034 29.325062 90)
			(size 0.519938 1.4986)
			(layers "F.Cu" "F.Mask" "F.Paste")
			(net "GND")
		)
		(pad "249" smd rect
			(at 2.050034 30.174946 90)
			(size 0.519938 1.4986)
			(layers "F.Cu" "F.Mask" "F.Paste")
			(net "M_J_CPU1_SB_DQS_DN<5>")
		)
		(pad "250" smd rect
			(at 2.050034 31.025084 90)
			(size 0.519938 1.4986)
			(layers "F.Cu" "F.Mask" "F.Paste")
			(net "M_J_CPU1_SB_DQS_DP<5>")
		)
		(pad "251" smd rect
			(at 2.050034 31.874968 90)
			(size 0.519938 1.4986)
			(layers "F.Cu" "F.Mask" "F.Paste")
			(net "GND")
		)
		(pad "252" smd rect
			(at 2.050034 32.725106 90)
			(size 0.519938 1.4986)
			(layers "F.Cu" "F.Mask" "F.Paste")
			(net "M_J_CPU1_SB_DQ<6>")
		)
		(pad "253" smd rect
			(at 2.050034 33.57499 90)
			(size 0.519938 1.4986)
			(layers "F.Cu" "F.Mask" "F.Paste")
			(net "GND")
		)
		(pad "254" smd rect
			(at 2.050034 34.425128 90)
			(size 0.519938 1.4986)
			(layers "F.Cu" "F.Mask" "F.Paste")
			(net "M_J_CPU1_SB_DQ<7>")
		)
		(pad "255" smd rect
			(at 2.050034 35.275012 90)
			(size 0.519938 1.4986)
			(layers "F.Cu" "F.Mask" "F.Paste")
			(net "GND")
		)
		(pad "256" smd rect
			(at 2.050034 36.124896 90)
			(size 0.519938 1.4986)
			(layers "F.Cu" "F.Mask" "F.Paste")
			(net "M_J_CPU1_SB_DQ<10>")
		)
		(pad "257" smd rect
			(at 2.050034 36.975034 90)
			(size 0.519938 1.4986)
			(layers "F.Cu" "F.Mask" "F.Paste")
			(net "GND")
		)
		(pad "258" smd rect
			(at 2.050034 37.824918 90)
			(size 0.519938 1.4986)
			(layers "F.Cu" "F.Mask" "F.Paste")
			(net "M_J_CPU1_SB_DQ<11>")
		)
		(pad "259" smd rect
			(at 2.050034 38.675056 90)
			(size 0.519938 1.4986)
			(layers "F.Cu" "F.Mask" "F.Paste")
			(net "GND")
		)
		(pad "260" smd rect
			(at 2.050034 39.52494 90)
			(size 0.519938 1.4986)
			(layers "F.Cu" "F.Mask" "F.Paste")
			(net "M_J_CPU1_SB_DQS_DN<6>")
		)
		(pad "261" smd rect
			(at 2.050034 40.375078 90)
			(size 0.519938 1.4986)
			(layers "F.Cu" "F.Mask" "F.Paste")
			(net "M_J_CPU1_SB_DQS_DP<6>")
		)
		(pad "262" smd rect
			(at 2.050034 41.224962 90)
			(size 0.519938 1.4986)
			(layers "F.Cu" "F.Mask" "F.Paste")
			(net "GND")
		)
		(pad "263" smd rect
			(at 2.050034 42.0751 90)
			(size 0.519938 1.4986)
			(layers "F.Cu" "F.Mask" "F.Paste")
			(net "M_J_CPU1_SB_DQ<14>")
		)
		(pad "264" smd rect
			(at 2.050034 42.924984 90)
			(size 0.519938 1.4986)
			(layers "F.Cu" "F.Mask" "F.Paste")
			(net "GND")
		)
		(pad "265" smd rect
			(at 2.050034 43.775122 90)
			(size 0.519938 1.4986)
			(layers "F.Cu" "F.Mask" "F.Paste")
			(net "M_J_CPU1_SB_DQ<15>")
		)
		(pad "266" smd rect
			(at 2.050034 44.625006 90)
			(size 0.519938 1.4986)
			(layers "F.Cu" "F.Mask" "F.Paste")
			(net "GND")
		)
		(pad "267" smd rect
			(at 2.050034 45.47489 90)
			(size 0.519938 1.4986)
			(layers "F.Cu" "F.Mask" "F.Paste")
			(net "M_J_CPU1_SB_DQ<18>")
		)
		(pad "268" smd rect
			(at 2.050034 46.325028 90)
			(size 0.519938 1.4986)
			(layers "F.Cu" "F.Mask" "F.Paste")
			(net "GND")
		)
		(pad "269" smd rect
			(at 2.050034 47.174912 90)
			(size 0.519938 1.4986)
			(layers "F.Cu" "F.Mask" "F.Paste")
			(net "M_J_CPU1_SB_DQ<19>")
		)
		(pad "270" smd rect
			(at 2.050034 48.02505 90)
			(size 0.519938 1.4986)
			(layers "F.Cu" "F.Mask" "F.Paste")
			(net "GND")
		)
		(pad "271" smd rect
			(at 2.050034 48.874934 90)
			(size 0.519938 1.4986)
			(layers "F.Cu" "F.Mask" "F.Paste")
			(net "M_J_CPU1_SB_DQS_DN<7>")
		)
		(pad "272" smd rect
			(at 2.050034 49.725072 90)
			(size 0.519938 1.4986)
			(layers "F.Cu" "F.Mask" "F.Paste")
			(net "M_J_CPU1_SB_DQS_DP<7>")
		)
		(pad "273" smd rect
			(at 2.050034 50.574956 90)
			(size 0.519938 1.4986)
			(layers "F.Cu" "F.Mask" "F.Paste")
			(net "GND")
		)
		(pad "274" smd rect
			(at 2.050034 51.425094 90)
			(size 0.519938 1.4986)
			(layers "F.Cu" "F.Mask" "F.Paste")
			(net "M_J_CPU1_SB_DQ<22>")
		)
		(pad "275" smd rect
			(at 2.050034 52.274978 90)
			(size 0.519938 1.4986)
			(layers "F.Cu" "F.Mask" "F.Paste")
			(net "GND")
		)
		(pad "276" smd rect
			(at 2.050034 53.125116 90)
			(size 0.519938 1.4986)
			(layers "F.Cu" "F.Mask" "F.Paste")
			(net "M_J_CPU1_SB_DQ<23>")
		)
		(pad "277" smd rect
			(at 2.050034 53.975 90)
			(size 0.519938 1.4986)
			(layers "F.Cu" "F.Mask" "F.Paste")
			(net "GND")
		)
		(pad "278" smd rect
			(at 2.050034 54.824884 90)
			(size 0.519938 1.4986)
			(layers "F.Cu" "F.Mask" "F.Paste")
			(net "M_J_CPU1_SB_DQ<26>")
		)
		(pad "279" smd rect
			(at 2.050034 55.675022 90)
			(size 0.519938 1.4986)
			(layers "F.Cu" "F.Mask" "F.Paste")
			(net "GND")
		)
		(pad "280" smd rect
			(at 2.050034 56.524906 90)
			(size 0.519938 1.4986)
			(layers "F.Cu" "F.Mask" "F.Paste")
			(net "M_J_CPU1_SB_DQ<27>")
		)
		(pad "281" smd rect
			(at 2.050034 57.375044 90)
			(size 0.519938 1.4986)
			(layers "F.Cu" "F.Mask" "F.Paste")
			(net "GND")
		)
		(pad "282" smd rect
			(at 2.050034 58.224928 90)
			(size 0.519938 1.4986)
			(layers "F.Cu" "F.Mask" "F.Paste")
			(net "M_J_CPU1_SB_DQS_DN<8>")
		)
		(pad "283" smd rect
			(at 2.050034 59.075066 90)
			(size 0.519938 1.4986)
			(layers "F.Cu" "F.Mask" "F.Paste")
			(net "M_J_CPU1_SB_DQS_DP<8>")
		)
		(pad "284" smd rect
			(at 2.050034 59.92495 90)
			(size 0.519938 1.4986)
			(layers "F.Cu" "F.Mask" "F.Paste")
			(net "GND")
		)
		(pad "285" smd rect
			(at 2.050034 60.775088 90)
			(size 0.519938 1.4986)
			(layers "F.Cu" "F.Mask" "F.Paste")
			(net "M_J_CPU1_SB_DQ<30>")
		)
		(pad "286" smd rect
			(at 2.050034 61.624972 90)
			(size 0.519938 1.4986)
			(layers "F.Cu" "F.Mask" "F.Paste")
			(net "GND")
		)
		(pad "287" smd rect
			(at 2.050034 62.47511 90)
			(size 0.519938 1.4986)
			(layers "F.Cu" "F.Mask" "F.Paste")
			(net "M_J_CPU1_SB_DQ<31>")
		)
		(pad "288" smd rect
			(at 2.050034 63.324994 90)
			(size 0.519938 1.4986)
			(layers "F.Cu" "F.Mask" "F.Paste")
			(net "GND")
		)
		(pad "G1" thru_hole oval
			(at 0 -68.97497 90)
			(size 1.7272 3.4798)
			(drill oval 1.2192 2.4638)
			(layers "*.Cu" "*.Mask")
			(remove_unused_layers no)
			(net "GND")
			(clearance 0.127)
			(thermal_gap 0.127)
		)
		(pad "G2" thru_hole oval
			(at 0 3.875024 90)
			(size 1.7272 3.4798)
			(drill oval 1.2192 2.4638)
			(layers "*.Cu" "*.Mask")
			(remove_unused_layers no)
			(net "GND")
			(clearance 0.127)
			(thermal_gap 0.127)
		)
		(pad "G3" thru_hole oval
			(at 0 68.97497 90)
			(size 1.7272 3.4798)
			(drill oval 1.2192 2.4638)
			(layers "*.Cu" "*.Mask")
			(remove_unused_layers no)
			(net "GND")
			(clearance 0.127)
			(thermal_gap 0.127)
		)
	)
)
